# T6G (Grand Teton) — schematic netlist excerpt (pin names and nets, part order shuffled) for the footprints in the layout excerpt that follows; sources: Cadence DE-HDL packaged netlist, KiCad conversion of 04192023_DAF0TMB3IC0_F0TG_MB_C_brd_V02_OCP.brd

R2920  Q_RES  100K 1% CHIP  pkg 0402LF  page 127 : A = P3V3_AUX ; B = BIC_MONITER_ISO
R1404  Q_RES  4.7K 5% CHIP  pkg 0201LF  page 298 : A = CLKREQ_RT_CPU0_P2_N ; B = GND
R5010  Q_RES  1K 1% EMPTY  pkg 0402LF  page 159 : A = PVDD11_S3_P1 ; B = I3C_SPD_DDRAF_CPU1_LVC1_SCL

(kicad_pcb
	(version 20260206)
	(generator "pcbnew")
	(generator_version "10.0")
	(general
		(thickness 1.6)
		(legacy_teardrops no)
	)
	(paper "A4")
	(title_block
		(title "04192023_DAF0TMB3IC0_F0TG_MB_C_brd_V02_OCP.brd")
		(comment 1 "Grand Teton / footprints 4803-4805 of 8354")
	)
	(layers
		(0 "F.Cu" signal "TOP")
		(4 "In1.Cu" signal "GND")
		(6 "In2.Cu" signal "IN1")
		(8 "In3.Cu" signal "GND1")
		(10 "In4.Cu" signal "IN2")
		(12 "In5.Cu" signal "GND2")
		(14 "In6.Cu" signal "IN3")
		(16 "In7.Cu" signal "GND3")
		(18 "In8.Cu" signal "VCC")
		(20 "In9.Cu" signal "VCC1")
		(22 "In10.Cu" signal "GND4")
		(24 "In11.Cu" signal "IN4")
		(26 "In12.Cu" signal "GND5")
		(28 "In13.Cu" signal "IN5")
		(30 "In14.Cu" signal "GND6")
		(32 "In15.Cu" signal "IN6")
		(34 "In16.Cu" signal "GND7")
		(2 "B.Cu" signal "BOTTOM")
		(9 "F.Adhes" user "F.Adhesive")
		(11 "B.Adhes" user "B.Adhesive")
		(13 "F.Paste" user "Package Geometry/Pastemask Top")
		(15 "B.Paste" user "Package Geometry/Pastemask Bottom")
		(5 "F.SilkS" user "Ref Des/Silkscreen Top")
		(7 "B.SilkS" user "Ref Des/Silkscreen Bottom")
		(1 "F.Mask" user "Board Geometry/Soldermask Top")
		(3 "B.Mask" user "Board Geometry/Soldermask Bottom")
		(17 "Dwgs.User" user "User.Drawings")
		(19 "Cmts.User" user "User.Comments")
		(21 "Eco1.User" user "User.Eco1")
		(23 "Eco2.User" user "User.Eco2")
		(25 "Edge.Cuts" user "Board Geometry/Outline")
		(27 "Margin" user)
		(31 "F.CrtYd" user "Package Geometry/Place Bound Top")
		(29 "B.CrtYd" user "Package Geometry/Place Bound Bottom")
		(35 "F.Fab" user "Ref Des/Assembly Top")
		(33 "B.Fab" user "Ref Des/Assembly Bottom")
	)
	(footprint ""
		(layer "F.Cu")
		(at 163.4236 -438.912)
		(property "Reference" "R2920"
			(at 0 0 0)
			(layer "F.SilkS")
			(hide yes)
			(effects
				(font
					(size 1.27 1.27)
				)
			)
		)
		(property "Value" ""
			(at 0 0 0)
			(layer "F.Fab")
			(effects
				(font
					(size 1.27 1.27)
				)
			)
		)
		(duplicate_pad_numbers_are_jumpers no)
		(fp_line
			(start -0.7874 -0.4064)
			(end 0.7874 -0.4064)
			(stroke
				(width 0.1524)
				(type default)
			)
			(layer "F.SilkS")
		)
		(fp_line
			(start -0.7874 0.4064)
			(end -0.7874 -0.4064)
			(stroke
				(width 0.1524)
				(type default)
			)
			(layer "F.SilkS")
		)
		(fp_line
			(start 0.7874 -0.4064)
			(end 0.7874 0.4064)
			(stroke
				(width 0.1524)
				(type default)
			)
			(layer "F.SilkS")
		)
		(fp_line
			(start 0.7874 0.4064)
			(end -0.7874 0.4064)
			(stroke
				(width 0.1524)
				(type default)
			)
			(layer "F.SilkS")
		)
		(fp_line
			(start -0.67945 -0.305054)
			(end -0.12065 -0.305054)
			(stroke
				(width 0.1)
				(type default)
			)
			(layer "F.Fab")
		)
		(fp_line
			(start -0.67945 0.3048)
			(end -0.67945 -0.305054)
			(stroke
				(width 0.1)
				(type default)
			)
			(layer "F.Fab")
		)
		(fp_line
			(start -0.12065 -0.305054)
			(end -0.12065 -0.2794)
			(stroke
				(width 0.1)
				(type default)
			)
			(layer "F.Fab")
		)
		(fp_line
			(start -0.12065 -0.2794)
			(end 0.12065 -0.2794)
			(stroke
				(width 0.1)
				(type default)
			)
			(layer "F.Fab")
		)
		(fp_line
			(start -0.12065 0.2794)
			(end -0.12065 0.3048)
			(stroke
				(width 0.1)
				(type default)
			)
			(layer "F.Fab")
		)
		(fp_line
			(start -0.12065 0.3048)
			(end -0.67945 0.3048)
			(stroke
				(width 0.1)
				(type default)
			)
			(layer "F.Fab")
		)
		(fp_line
			(start 0.120396 0.2794)
			(end -0.12065 0.2794)
			(stroke
				(width 0.1)
				(type default)
			)
			(layer "F.Fab")
		)
		(fp_line
			(start 0.120396 0.3048)
			(end 0.120396 0.2794)
			(stroke
				(width 0.1)
				(type default)
			)
			(layer "F.Fab")
		)
		(fp_line
			(start 0.12065 -0.3048)
			(end 0.67945 -0.3048)
			(stroke
				(width 0.1)
				(type default)
			)
			(layer "F.Fab")
		)
		(fp_line
			(start 0.12065 -0.2794)
			(end 0.12065 -0.3048)
			(stroke
				(width 0.1)
				(type default)
			)
			(layer "F.Fab")
		)
		(fp_line
			(start 0.67945 -0.3048)
			(end 0.67945 0.3048)
			(stroke
				(width 0.1)
				(type default)
			)
			(layer "F.Fab")
		)
		(fp_line
			(start 0.67945 0.3048)
			(end 0.120396 0.3048)
			(stroke
				(width 0.1)
				(type default)
			)
			(layer "F.Fab")
		)
		(pad "1" smd circle
			(at -0.40005 0)
			(size 0 0)
			(layers "F.Cu" "F.Mask" "F.Paste")
			(net "P3V3_AUX")
		)
		(pad "2" smd circle
			(at 0.40005 0)
			(size 0 0)
			(layers "F.Cu" "F.Mask" "F.Paste")
			(net "BIC_MONITER_ISO")
		)
	)
	(footprint ""
		(layer "F.Cu")
		(at 425.79163 -389.802116 -90)
		(property "Reference" "R1404"
			(at 0 0 270)
			(layer "F.SilkS")
			(hide yes)
			(effects
				(font
					(size 1.27 1.27)
				)
			)
		)
		(property "Value" ""
			(at 0 0 270)
			(layer "F.Fab")
			(effects
				(font
					(size 1.27 1.27)
				)
			)
		)
		(duplicate_pad_numbers_are_jumpers no)
		(fp_line
			(start -0.32512 0.175006)
			(end -0.32512 -0.175006)
			(stroke
				(width 0.1)
				(type default)
			)
			(layer "F.Fab")
		)
		(fp_line
			(start 0.32512 0.175006)
			(end -0.32512 0.175006)
			(stroke
				(width 0.1)
				(type default)
			)
			(layer "F.Fab")
		)
		(fp_line
			(start -0.32512 -0.175006)
			(end 0.32512 -0.175006)
			(stroke
				(width 0.1)
				(type default)
			)
			(layer "F.Fab")
		)
		(fp_line
			(start 0.32512 -0.175006)
			(end 0.32512 0.175006)
			(stroke
				(width 0.1)
				(type default)
			)
			(layer "F.Fab")
		)
		(pad "1" smd rect
			(at -0.2667 0 270)
			(size 0.3048 0.381)
			(layers "F.Cu" "F.Mask" "F.Paste")
			(net "CLKREQ_RT_CPU0_P2_N")
		)
		(pad "2" smd rect
			(at 0.2667 0 90)
			(size 0.3048 0.381)
			(layers "F.Cu" "F.Mask" "F.Paste")
			(net "GND")
		)
	)
	(footprint ""
		(layer "F.Cu")
		(at 34.665158 -171.52366)
		(property "Reference" "R5010"
			(at 0 0 0)
			(layer "F.SilkS")
			(hide yes)
			(effects
				(font
					(size 1.27 1.27)
				)
			)
		)
		(property "Value" ""
			(at 0 0 0)
			(layer "F.Fab")
			(effects
				(font
					(size 1.27 1.27)
				)
			)
		)
		(duplicate_pad_numbers_are_jumpers no)
		(fp_line
			(start -0.7874 -0.4064)
			(end 0.7874 -0.4064)
			(stroke
				(width 0.1524)
				(type default)
			)
			(layer "F.SilkS")
		)
		(fp_line
			(start -0.7874 0.4064)
			(end -0.7874 -0.4064)
			(stroke
				(width 0.1524)
				(type default)
			)
			(layer "F.SilkS")
		)
		(fp_line
			(start 0.7874 -0.4064)
			(end 0.7874 0.4064)
			(stroke
				(width 0.1524)
				(type default)
			)
			(layer "F.SilkS")
		)
		(fp_line
			(start 0.7874 0.4064)
			(end -0.7874 0.4064)
			(stroke
				(width 0.1524)
				(type default)
			)
			(layer "F.SilkS")
		)
		(fp_line
			(start -0.67945 -0.305054)
			(end -0.12065 -0.305054)
			(stroke
				(width 0.1)
				(type default)
			)
			(layer "F.Fab")
		)
		(fp_line
			(start -0.67945 0.3048)
			(end -0.67945 -0.305054)
			(stroke
				(width 0.1)
				(type default)
			)
			(layer "F.Fab")
		)
		(fp_line
			(start -0.12065 -0.305054)
			(end -0.12065 -0.2794)
			(stroke
				(width 0.1)
				(type default)
			)
			(layer "F.Fab")
		)
		(fp_line
			(start -0.12065 -0.2794)
			(end 0.12065 -0.2794)
			(stroke
				(width 0.1)
				(type default)
			)
			(layer "F.Fab")
		)
		(fp_line
			(start -0.12065 0.2794)
			(end -0.12065 0.3048)
			(stroke
				(width 0.1)
				(type default)
			)
			(layer "F.Fab")
		)
		(fp_line
			(start -0.12065 0.3048)
			(end -0.67945 0.3048)
			(stroke
				(width 0.1)
				(type default)
			)
			(layer "F.Fab")
		)
		(fp_line
			(start 0.120396 0.2794)
			(end -0.12065 0.2794)
			(stroke
				(width 0.1)
				(type default)
			)
			(layer "F.Fab")
		)
		(fp_line
			(start 0.120396 0.3048)
			(end 0.120396 0.2794)
			(stroke
				(width 0.1)
				(type default)
			)
			(layer "F.Fab")
		)
		(fp_line
			(start 0.12065 -0.3048)
			(end 0.67945 -0.3048)
			(stroke
				(width 0.1)
				(type default)
			)
			(layer "F.Fab")
		)
		(fp_line
			(start 0.12065 -0.2794)
			(end 0.12065 -0.3048)
			(stroke
				(width 0.1)
				(type default)
			)
			(layer "F.Fab")
		)
		(fp_line
			(start 0.67945 -0.3048)
			(end 0.67945 0.3048)
			(stroke
				(width 0.1)
				(type default)
			)
			(layer "F.Fab")
		)
		(fp_line
			(start 0.67945 0.3048)
			(end 0.120396 0.3048)
			(stroke
				(width 0.1)
				(type default)
			)
			(layer "F.Fab")
		)
		(pad "1" smd circle
			(at -0.40005 0)
			(size 0 0)
			(layers "F.Cu" "F.Mask" "F.Paste")
			(net "PVDD11_S3_P1")
		)
		(pad "2" smd circle
			(at 0.40005 0)
			(size 0 0)
			(layers "F.Cu" "F.Mask" "F.Paste")
			(net "I3C_SPD_DDRAF_CPU1_LVC1_SCL")
		)
	)
)
